#ISCELL
  pure_quanta quanta_title_block_c *
  *
#ISCELL
  standard tap *
  page59_i10
#ISCELL
  standard tap *
  page59_i11
#ISCELL
  standard tap *
  page59_i12
#ISCELL
  standard tap *
  page59_i13
#ISCELL
  standard tap *
  page59_i14
#ISCELL
  standard tap *
  page59_i15
#ISCELL
  standard tap *
  page59_i16
#ISCELL
  standard tap *
  page59_i17
#ISCELL
  standard tap *
  page59_i18
#ISCELL
  standard tap *
  page59_i19
#CELL
  pure_quanta socket4677_azif0045p001c01cs *
  page59_i20
#ISCELL
  standard tap *
  page59_i21
#ISCELL
  standard tap *
  page59_i22
#ISCELL
  standard tap *
  page59_i23
#ISCELL
  standard tap *
  page59_i24
#ISCELL
  standard tap *
  page59_i25
#ISCELL
  standard tap *
  page59_i26
#ISCELL
  standard tap *
  page59_i27
#ISCELL
  standard tap *
  page59_i28
#ISCELL
  standard tap *
  page59_i29
#ISCELL
  standard tap *
  page59_i30
#ISCELL
  standard tap *
  page59_i31
#ISCELL
  standard tap *
  page59_i32
#ISCELL
  standard tap *
  page59_i33
#ISCELL
  standard tap *
  page59_i34
#ISCELL
  standard tap *
  page59_i35
#ISCELL
  standard tap *
  page59_i36
#ISCELL
  standard tap *
  page59_i4
#ISCELL
  standard tap *
  page59_i5
#ISCELL
  standard tap *
  page59_i6
#ISCELL
  standard tap *
  page59_i7
#ISCELL
  standard tap *
  page59_i8
#ISCELL
  standard tap *
  page59_i9
